(kicad_pcb
	(version 20260206)
	(generator "pcbnew")
	(generator_version "10.0")
	(general
		(thickness 1.6)
		(legacy_teardrops no)
	)
	(paper "A4")
	(title_block
		(title "12092022_DA0F0TFB6D0_F0T_FAN_BOARD_MP5048_D_brd_v02_OCP.brd")
		(comment 1 "Grand Teton / footprints 25-30 of 924")
	)
	(layers
		(0 "F.Cu" signal "TOP")
		(4 "In1.Cu" signal "GND")
		(6 "In2.Cu" signal "IN1")
		(8 "In3.Cu" signal "IN2")
		(10 "In4.Cu" signal "GND1")
		(2 "B.Cu" signal "BOTTOM")
		(9 "F.Adhes" user "F.Adhesive")
		(11 "B.Adhes" user "B.Adhesive")
		(13 "F.Paste" user "Package Geometry/Pastemask Top")
		(15 "B.Paste" user "Package Geometry/Pastemask Bottom")
		(5 "F.SilkS" user "Ref Des/Silkscreen Top")
		(7 "B.SilkS" user "Ref Des/Silkscreen Bottom")
		(1 "F.Mask" user "Board Geometry/Soldermask Top")
		(3 "B.Mask" user "Board Geometry/Soldermask Bottom")
		(17 "Dwgs.User" user "User.Drawings")
		(19 "Cmts.User" user "User.Comments")
		(21 "Eco1.User" user "User.Eco1")
		(23 "Eco2.User" user "User.Eco2")
		(25 "Edge.Cuts" user "Board Geometry/Outline")
		(27 "Margin" user)
		(31 "F.CrtYd" user "Package Geometry/Place Bound Top")
		(29 "B.CrtYd" user "Package Geometry/Place Bound Bottom")
		(35 "F.Fab" user "Ref Des/Assembly Top")
		(33 "B.Fab" user "Ref Des/Assembly Bottom")
	)
	(footprint ""
		(layer "F.Cu")
		(at 16.891 -205.105 180)
		(property "Reference" "R5535"
			(at 0 0 180)
			(layer "F.SilkS")
			(hide yes)
			(effects
				(font
					(size 1.27 1.27)
				)
			)
		)
		(property "Value" ""
			(at 0 0 180)
			(layer "F.Fab")
			(effects
				(font
					(size 1.27 1.27)
				)
			)
		)
		(duplicate_pad_numbers_are_jumpers no)
		(fp_line
			(start 0.7874 0.4064)
			(end -0.7874 0.4064)
			(stroke
				(width 0.1524)
				(type default)
			)
			(layer "F.SilkS")
		)
		(fp_line
			(start 0.7874 -0.4064)
			(end 0.7874 0.4064)
			(stroke
				(width 0.1524)
				(type default)
			)
			(layer "F.SilkS")
		)
		(fp_line
			(start -0.7874 0.4064)
			(end -0.7874 -0.4064)
			(stroke
				(width 0.1524)
				(type default)
			)
			(layer "F.SilkS")
		)
		(fp_line
			(start -0.7874 -0.4064)
			(end 0.7874 -0.4064)
			(stroke
				(width 0.1524)
				(type default)
			)
			(layer "F.SilkS")
		)
		(fp_line
			(start 0.67945 0.3048)
			(end 0.120396 0.3048)
			(stroke
				(width 0.1)
				(type default)
			)
			(layer "F.Fab")
		)
		(fp_line
			(start 0.67945 -0.3048)
			(end 0.67945 0.3048)
			(stroke
				(width 0.1)
				(type default)
			)
			(layer "F.Fab")
		)
		(fp_line
			(start 0.12065 -0.2794)
			(end 0.12065 -0.3048)
			(stroke
				(width 0.1)
				(type default)
			)
			(layer "F.Fab")
		)
		(fp_line
			(start 0.12065 -0.3048)
			(end 0.67945 -0.3048)
			(stroke
				(width 0.1)
				(type default)
			)
			(layer "F.Fab")
		)
		(fp_line
			(start 0.120396 0.3048)
			(end 0.120396 0.2794)
			(stroke
				(width 0.1)
				(type default)
			)
			(layer "F.Fab")
		)
		(fp_line
			(start 0.120396 0.2794)
			(end -0.12065 0.2794)
			(stroke
				(width 0.1)
				(type default)
			)
			(layer "F.Fab")
		)
		(fp_line
			(start -0.12065 0.3048)
			(end -0.67945 0.3048)
			(stroke
				(width 0.1)
				(type default)
			)
			(layer "F.Fab")
		)
		(fp_line
			(start -0.12065 0.2794)
			(end -0.12065 0.3048)
			(stroke
				(width 0.1)
				(type default)
			)
			(layer "F.Fab")
		)
		(fp_line
			(start -0.12065 -0.2794)
			(end 0.12065 -0.2794)
			(stroke
				(width 0.1)
				(type default)
			)
			(layer "F.Fab")
		)
		(fp_line
			(start -0.12065 -0.305054)
			(end -0.12065 -0.2794)
			(stroke
				(width 0.1)
				(type default)
			)
			(layer "F.Fab")
		)
		(fp_line
			(start -0.67945 0.3048)
			(end -0.67945 -0.305054)
			(stroke
				(width 0.1)
				(type default)
			)
			(layer "F.Fab")
		)
		(fp_line
			(start -0.67945 -0.305054)
			(end -0.12065 -0.305054)
			(stroke
				(width 0.1)
				(type default)
			)
			(layer "F.Fab")
		)
		(pad "1" smd rect
			(at -0.40005 0)
			(size 0.4572 0.508)
			(layers "F.Cu" "F.Mask" "F.Paste")
			(net "P12V_LED_FAN6")
		)
		(pad "2" smd rect
			(at 0.40005 0)
			(size 0.4572 0.508)
			(layers "F.Cu" "F.Mask" "F.Paste")
			(net "FAN_6_FAIL_LED_R_N")
		)
	)
	(footprint ""
		(layer "F.Cu")
		(at 21.717 -28.194 90)
		(property "Reference" "C2089"
			(at 0 0 90)
			(layer "F.SilkS")
			(hide yes)
			(effects
				(font
					(size 1.27 1.27)
				)
			)
		)
		(property "Value" ""
			(at 0 0 90)
			(layer "F.Fab")
			(effects
				(font
					(size 1.27 1.27)
				)
			)
		)
		(duplicate_pad_numbers_are_jumpers no)
		(fp_line
			(start 0.7874 -0.4064)
			(end 0.7874 0.4064)
			(stroke
				(width 0.1524)
				(type default)
			)
			(layer "F.SilkS")
		)
		(fp_line
			(start -0.7874 -0.4064)
			(end 0.7874 -0.4064)
			(stroke
				(width 0.1524)
				(type default)
			)
			(layer "F.SilkS")
		)
		(fp_line
			(start 0.7874 0.4064)
			(end -0.7874 0.4064)
			(stroke
				(width 0.1524)
				(type default)
			)
			(layer "F.SilkS")
		)
		(fp_line
			(start -0.7874 0.4064)
			(end -0.7874 -0.4064)
			(stroke
				(width 0.1524)
				(type default)
			)
			(layer "F.SilkS")
		)
		(fp_line
			(start -0.12065 -0.305054)
			(end -0.12065 -0.2794)
			(stroke
				(width 0.1)
				(type default)
			)
			(layer "F.Fab")
		)
		(fp_line
			(start -0.67945 -0.305054)
			(end -0.12065 -0.305054)
			(stroke
				(width 0.1)
				(type default)
			)
			(layer "F.Fab")
		)
		(fp_line
			(start 0.67945 -0.3048)
			(end 0.67945 0.3048)
			(stroke
				(width 0.1)
				(type default)
			)
			(layer "F.Fab")
		)
		(fp_line
			(start 0.12065 -0.3048)
			(end 0.67945 -0.3048)
			(stroke
				(width 0.1)
				(type default)
			)
			(layer "F.Fab")
		)
		(fp_line
			(start 0.12065 -0.2794)
			(end 0.12065 -0.3048)
			(stroke
				(width 0.1)
				(type default)
			)
			(layer "F.Fab")
		)
		(fp_line
			(start -0.12065 -0.2794)
			(end 0.12065 -0.2794)
			(stroke
				(width 0.1)
				(type default)
			)
			(layer "F.Fab")
		)
		(fp_line
			(start 0.120396 0.2794)
			(end -0.12065 0.2794)
			(stroke
				(width 0.1)
				(type default)
			)
			(layer "F.Fab")
		)
		(fp_line
			(start -0.12065 0.2794)
			(end -0.12065 0.3048)
			(stroke
				(width 0.1)
				(type default)
			)
			(layer "F.Fab")
		)
		(fp_line
			(start 0.67945 0.3048)
			(end 0.120396 0.3048)
			(stroke
				(width 0.1)
				(type default)
			)
			(layer "F.Fab")
		)
		(fp_line
			(start 0.120396 0.3048)
			(end 0.120396 0.2794)
			(stroke
				(width 0.1)
				(type default)
			)
			(layer "F.Fab")
		)
		(fp_line
			(start -0.12065 0.3048)
			(end -0.67945 0.3048)
			(stroke
				(width 0.1)
				(type default)
			)
			(layer "F.Fab")
		)
		(fp_line
			(start -0.67945 0.3048)
			(end -0.67945 -0.305054)
			(stroke
				(width 0.1)
				(type default)
			)
			(layer "F.Fab")
		)
		(pad "1" smd circle
			(at -0.40005 0 90)
			(size 0 0)
			(layers "F.Cu" "F.Mask" "F.Paste")
			(net "P3V3_AUX")
		)
		(pad "2" smd circle
			(at 0.40005 0 90)
			(size 0 0)
			(layers "F.Cu" "F.Mask" "F.Paste")
			(net "GND")
		)
	)
	(footprint ""
		(layer "F.Cu")
		(at 48.768 -31.623 180)
		(property "Reference" "R5695"
			(at 0 0 180)
			(layer "F.SilkS")
			(hide yes)
			(effects
				(font
					(size 1.27 1.27)
				)
			)
		)
		(property "Value" ""
			(at 0 0 180)
			(layer "F.Fab")
			(effects
				(font
					(size 1.27 1.27)
				)
			)
		)
		(duplicate_pad_numbers_are_jumpers no)
		(fp_line
			(start 0.7874 0.4064)
			(end -0.7874 0.4064)
			(stroke
				(width 0.1524)
				(type default)
			)
			(layer "F.SilkS")
		)
		(fp_line
			(start 0.7874 -0.4064)
			(end 0.7874 0.4064)
			(stroke
				(width 0.1524)
				(type default)
			)
			(layer "F.SilkS")
		)
		(fp_line
			(start -0.7874 0.4064)
			(end -0.7874 -0.4064)
			(stroke
				(width 0.1524)
				(type default)
			)
			(layer "F.SilkS")
		)
		(fp_line
			(start -0.7874 -0.4064)
			(end 0.7874 -0.4064)
			(stroke
				(width 0.1524)
				(type default)
			)
			(layer "F.SilkS")
		)
		(fp_line
			(start 0.67945 0.3048)
			(end 0.120396 0.3048)
			(stroke
				(width 0.1)
				(type default)
			)
			(layer "F.Fab")
		)
		(fp_line
			(start 0.67945 -0.3048)
			(end 0.67945 0.3048)
			(stroke
				(width 0.1)
				(type default)
			)
			(layer "F.Fab")
		)
		(fp_line
			(start 0.12065 -0.2794)
			(end 0.12065 -0.3048)
			(stroke
				(width 0.1)
				(type default)
			)
			(layer "F.Fab")
		)
		(fp_line
			(start 0.12065 -0.3048)
			(end 0.67945 -0.3048)
			(stroke
				(width 0.1)
				(type default)
			)
			(layer "F.Fab")
		)
		(fp_line
			(start 0.120396 0.3048)
			(end 0.120396 0.2794)
			(stroke
				(width 0.1)
				(type default)
			)
			(layer "F.Fab")
		)
		(fp_line
			(start 0.120396 0.2794)
			(end -0.12065 0.2794)
			(stroke
				(width 0.1)
				(type default)
			)
			(layer "F.Fab")
		)
		(fp_line
			(start -0.12065 0.3048)
			(end -0.67945 0.3048)
			(stroke
				(width 0.1)
				(type default)
			)
			(layer "F.Fab")
		)
		(fp_line
			(start -0.12065 0.2794)
			(end -0.12065 0.3048)
			(stroke
				(width 0.1)
				(type default)
			)
			(layer "F.Fab")
		)
		(fp_line
			(start -0.12065 -0.2794)
			(end 0.12065 -0.2794)
			(stroke
				(width 0.1)
				(type default)
			)
			(layer "F.Fab")
		)
		(fp_line
			(start -0.12065 -0.305054)
			(end -0.12065 -0.2794)
			(stroke
				(width 0.1)
				(type default)
			)
			(layer "F.Fab")
		)
		(fp_line
			(start -0.67945 0.3048)
			(end -0.67945 -0.305054)
			(stroke
				(width 0.1)
				(type default)
			)
			(layer "F.Fab")
		)
		(fp_line
			(start -0.67945 -0.305054)
			(end -0.12065 -0.305054)
			(stroke
				(width 0.1)
				(type default)
			)
			(layer "F.Fab")
		)
		(pad "1" smd rect
			(at -0.40005 0)
			(size 0.4572 0.508)
			(layers "F.Cu" "F.Mask" "F.Paste")
			(net "P12V_LED_FAN3")
		)
		(pad "2" smd rect
			(at 0.40005 0)
			(size 0.4572 0.508)
			(layers "F.Cu" "F.Mask" "F.Paste")
			(net "P12V_LED_R_FAN3")
		)
	)
	(footprint ""
		(layer "F.Cu")
		(at 29.083 -199.898 -90)
		(property "Reference" "R5521"
			(at 0 0 270)
			(layer "F.SilkS")
			(hide yes)
			(effects
				(font
					(size 1.27 1.27)
				)
			)
		)
		(property "Value" ""
			(at 0 0 270)
			(layer "F.Fab")
			(effects
				(font
					(size 1.27 1.27)
				)
			)
		)
		(duplicate_pad_numbers_are_jumpers no)
		(fp_line
			(start -0.7874 0.4064)
			(end -0.7874 -0.4064)
			(stroke
				(width 0.1524)
				(type default)
			)
			(layer "F.SilkS")
		)
		(fp_line
			(start 0.7874 0.4064)
			(end -0.7874 0.4064)
			(stroke
				(width 0.1524)
				(type default)
			)
			(layer "F.SilkS")
		)
		(fp_line
			(start -0.7874 -0.4064)
			(end 0.7874 -0.4064)
			(stroke
				(width 0.1524)
				(type default)
			)
			(layer "F.SilkS")
		)
		(fp_line
			(start 0.7874 -0.4064)
			(end 0.7874 0.4064)
			(stroke
				(width 0.1524)
				(type default)
			)
			(layer "F.SilkS")
		)
		(fp_line
			(start -0.67945 0.3048)
			(end -0.67945 -0.305054)
			(stroke
				(width 0.1)
				(type default)
			)
			(layer "F.Fab")
		)
		(fp_line
			(start -0.12065 0.3048)
			(end -0.67945 0.3048)
			(stroke
				(width 0.1)
				(type default)
			)
			(layer "F.Fab")
		)
		(fp_line
			(start 0.120396 0.3048)
			(end 0.120396 0.2794)
			(stroke
				(width 0.1)
				(type default)
			)
			(layer "F.Fab")
		)
		(fp_line
			(start 0.67945 0.3048)
			(end 0.120396 0.3048)
			(stroke
				(width 0.1)
				(type default)
			)
			(layer "F.Fab")
		)
		(fp_line
			(start -0.12065 0.2794)
			(end -0.12065 0.3048)
			(stroke
				(width 0.1)
				(type default)
			)
			(layer "F.Fab")
		)
		(fp_line
			(start 0.120396 0.2794)
			(end -0.12065 0.2794)
			(stroke
				(width 0.1)
				(type default)
			)
			(layer "F.Fab")
		)
		(fp_line
			(start -0.12065 -0.2794)
			(end 0.12065 -0.2794)
			(stroke
				(width 0.1)
				(type default)
			)
			(layer "F.Fab")
		)
		(fp_line
			(start 0.12065 -0.2794)
			(end 0.12065 -0.3048)
			(stroke
				(width 0.1)
				(type default)
			)
			(layer "F.Fab")
		)
		(fp_line
			(start 0.12065 -0.3048)
			(end 0.67945 -0.3048)
			(stroke
				(width 0.1)
				(type default)
			)
			(layer "F.Fab")
		)
		(fp_line
			(start 0.67945 -0.3048)
			(end 0.67945 0.3048)
			(stroke
				(width 0.1)
				(type default)
			)
			(layer "F.Fab")
		)
		(fp_line
			(start -0.67945 -0.305054)
			(end -0.12065 -0.305054)
			(stroke
				(width 0.1)
				(type default)
			)
			(layer "F.Fab")
		)
		(fp_line
			(start -0.12065 -0.305054)
			(end -0.12065 -0.2794)
			(stroke
				(width 0.1)
				(type default)
			)
			(layer "F.Fab")
		)
		(pad "1" smd circle
			(at -0.40005 0 270)
			(size 0 0)
			(layers "F.Cu" "F.Mask" "F.Paste")
			(net "P3V3_AUX")
		)
		(pad "2" smd circle
			(at 0.40005 0 270)
			(size 0 0)
			(layers "F.Cu" "F.Mask" "F.Paste")
			(net "FAN_6_PWM")
		)
	)
	(footprint ""
		(layer "F.Cu")
		(at 27.305 -30.734 180)
		(property "Reference" "C2123"
			(at 0 0 180)
			(layer "F.SilkS")
			(hide yes)
			(effects
				(font
					(size 1.27 1.27)
				)
			)
		)
		(property "Value" ""
			(at 0 0 180)
			(layer "F.Fab")
			(effects
				(font
					(size 1.27 1.27)
				)
			)
		)
		(duplicate_pad_numbers_are_jumpers no)
		(fp_line
			(start 1.2954 0.5842)
			(end -1.2954 0.5842)
			(stroke
				(width 0.1524)
				(type default)
			)
			(layer "F.SilkS")
		)
		(fp_line
			(start 1.2954 -0.5842)
			(end 1.2954 0.5842)
			(stroke
				(width 0.1524)
				(type default)
			)
			(layer "F.SilkS")
		)
		(fp_line
			(start -1.2954 0.5842)
			(end -1.2954 -0.5842)
			(stroke
				(width 0.1524)
				(type default)
			)
			(layer "F.SilkS")
		)
		(fp_line
			(start -1.2954 -0.5842)
			(end 1.2954 -0.5842)
			(stroke
				(width 0.1524)
				(type default)
			)
			(layer "F.SilkS")
		)
		(fp_line
			(start 1.1938 0.4064)
			(end 0.8636 0.4064)
			(stroke
				(width 0.1)
				(type default)
			)
			(layer "F.Fab")
		)
		(fp_line
			(start 1.1938 -0.4064)
			(end 1.1938 0.4064)
			(stroke
				(width 0.1)
				(type default)
			)
			(layer "F.Fab")
		)
		(fp_line
			(start 0.8636 0.4572)
			(end -0.8636 0.4572)
			(stroke
				(width 0.1)
				(type default)
			)
			(layer "F.Fab")
		)
		(fp_line
			(start 0.8636 0.4064)
			(end 0.8636 0.4572)
			(stroke
				(width 0.1)
				(type default)
			)
			(layer "F.Fab")
		)
		(fp_line
			(start 0.8636 -0.4064)
			(end 1.1938 -0.4064)
			(stroke
				(width 0.1)
				(type default)
			)
			(layer "F.Fab")
		)
		(fp_line
			(start 0.8636 -0.4572)
			(end 0.8636 -0.4064)
			(stroke
				(width 0.1)
				(type default)
			)
			(layer "F.Fab")
		)
		(fp_line
			(start -0.8636 0.4572)
			(end -0.8636 0.4064)
			(stroke
				(width 0.1)
				(type default)
			)
			(layer "F.Fab")
		)
		(fp_line
			(start -0.8636 0.4064)
			(end -1.1938 0.4064)
			(stroke
				(width 0.1)
				(type default)
			)
			(layer "F.Fab")
		)
		(fp_line
			(start -0.8636 -0.4064)
			(end -0.8636 -0.4572)
			(stroke
				(width 0.1)
				(type default)
			)
			(layer "F.Fab")
		)
		(fp_line
			(start -0.8636 -0.4572)
			(end 0.8636 -0.4572)
			(stroke
				(width 0.1)
				(type default)
			)
			(layer "F.Fab")
		)
		(fp_line
			(start -1.1938 0.4064)
			(end -1.1938 -0.4064)
			(stroke
				(width 0.1)
				(type default)
			)
			(layer "F.Fab")
		)
		(fp_line
			(start -1.1938 -0.4064)
			(end -0.8636 -0.4064)
			(stroke
				(width 0.1)
				(type default)
			)
			(layer "F.Fab")
		)
		(pad "1" smd rect
			(at -0.7366 0 90)
			(size 0.7112 0.8128)
			(layers "F.Cu" "F.Mask" "F.Paste")
			(net "U408_D1")
		)
		(pad "2" smd rect
			(at 0.7366 0 90)
			(size 0.7112 0.8128)
			(layers "F.Cu" "F.Mask" "F.Paste")
			(net "GND")
		)
	)
	(footprint ""
		(layer "F.Cu")
		(at 3.429 -123.698)
		(property "Reference" "R5701"
			(at 0 0 0)
			(layer "F.SilkS")
			(hide yes)
			(effects
				(font
					(size 1.27 1.27)
				)
			)
		)
		(property "Value" ""
			(at 0 0 0)
			(layer "F.Fab")
			(effects
				(font
					(size 1.27 1.27)
				)
			)
		)
		(duplicate_pad_numbers_are_jumpers no)
		(fp_line
			(start -0.7874 -0.4064)
			(end 0.7874 -0.4064)
			(stroke
				(width 0.1524)
				(type default)
			)
			(layer "F.SilkS")
		)
		(fp_line
			(start -0.7874 0.4064)
			(end -0.7874 -0.4064)
			(stroke
				(width 0.1524)
				(type default)
			)
			(layer "F.SilkS")
		)
		(fp_line
			(start 0.7874 -0.4064)
			(end 0.7874 0.4064)
			(stroke
				(width 0.1524)
				(type default)
			)
			(layer "F.SilkS")
		)
		(fp_line
			(start 0.7874 0.4064)
			(end -0.7874 0.4064)
			(stroke
				(width 0.1524)
				(type default)
			)
			(layer "F.SilkS")
		)
		(fp_line
			(start -0.67945 -0.305054)
			(end -0.12065 -0.305054)
			(stroke
				(width 0.1)
				(type default)
			)
			(layer "F.Fab")
		)
		(fp_line
			(start -0.67945 0.3048)
			(end -0.67945 -0.305054)
			(stroke
				(width 0.1)
				(type default)
			)
			(layer "F.Fab")
		)
		(fp_line
			(start -0.12065 -0.305054)
			(end -0.12065 -0.2794)
			(stroke
				(width 0.1)
				(type default)
			)
			(layer "F.Fab")
		)
		(fp_line
			(start -0.12065 -0.2794)
			(end 0.12065 -0.2794)
			(stroke
				(width 0.1)
				(type default)
			)
			(layer "F.Fab")
		)
		(fp_line
			(start -0.12065 0.2794)
			(end -0.12065 0.3048)
			(stroke
				(width 0.1)
				(type default)
			)
			(layer "F.Fab")
		)
		(fp_line
			(start -0.12065 0.3048)
			(end -0.67945 0.3048)
			(stroke
				(width 0.1)
				(type default)
			)
			(layer "F.Fab")
		)
		(fp_line
			(start 0.120396 0.2794)
			(end -0.12065 0.2794)
			(stroke
				(width 0.1)
				(type default)
			)
			(layer "F.Fab")
		)
		(fp_line
			(start 0.120396 0.3048)
			(end 0.120396 0.2794)
			(stroke
				(width 0.1)
				(type default)
			)
			(layer "F.Fab")
		)
		(fp_line
			(start 0.12065 -0.3048)
			(end 0.67945 -0.3048)
			(stroke
				(width 0.1)
				(type default)
			)
			(layer "F.Fab")
		)
		(fp_line
			(start 0.12065 -0.2794)
			(end 0.12065 -0.3048)
			(stroke
				(width 0.1)
				(type default)
			)
			(layer "F.Fab")
		)
		(fp_line
			(start 0.67945 -0.3048)
			(end 0.67945 0.3048)
			(stroke
				(width 0.1)
				(type default)
			)
			(layer "F.Fab")
		)
		(fp_line
			(start 0.67945 0.3048)
			(end 0.120396 0.3048)
			(stroke
				(width 0.1)
				(type default)
			)
			(layer "F.Fab")
		)
		(pad "1" smd rect
			(at -0.40005 0 180)
			(size 0.4572 0.508)
			(layers "F.Cu" "F.Mask" "F.Paste")
			(net "P12V_LED_FAN5")
		)
		(pad "2" smd rect
			(at 0.40005 0 180)
			(size 0.4572 0.508)
			(layers "F.Cu" "F.Mask" "F.Paste")
			(net "P12V_LED_R_FAN5")
		)
	)
)
